(kicad_pcb
	(version 20260206)
	(generator "pcbnew")
	(generator_version "10.0")
	(general
		(thickness 1.6)
		(legacy_teardrops no)
	)
	(paper "A4")
	(title_block
		(title "01162023_DA0F0TEBIF0_F0T_Expander_BD_F_brd_V02_OCP.brd")
		(comment 1 "Grand Teton / footprints 9227-9235 of 9728")
	)
	(layers
		(0 "F.Cu" signal "TOP")
		(4 "In1.Cu" signal "GND")
		(6 "In2.Cu" signal "VCC")
		(8 "In3.Cu" signal "VCC1")
		(10 "In4.Cu" signal "GND1")
		(12 "In5.Cu" signal "IN1")
		(14 "In6.Cu" signal "GND2")
		(16 "In7.Cu" signal "IN2")
		(18 "In8.Cu" signal "GND3")
		(20 "In9.Cu" signal "IN3")
		(22 "In10.Cu" signal "GND4")
		(24 "In11.Cu" signal "IN4")
		(26 "In12.Cu" signal "GND5")
		(28 "In13.Cu" signal "IN5")
		(30 "In14.Cu" signal "GND6")
		(32 "In15.Cu" signal "IN6")
		(34 "In16.Cu" signal "GND7")
		(2 "B.Cu" signal "BOTTOM")
		(9 "F.Adhes" user "F.Adhesive")
		(11 "B.Adhes" user "B.Adhesive")
		(13 "F.Paste" user "Package Geometry/Pastemask Top")
		(15 "B.Paste" user "Package Geometry/Pastemask Bottom")
		(5 "F.SilkS" user "Ref Des/Silkscreen Top")
		(7 "B.SilkS" user "Ref Des/Silkscreen Bottom")
		(1 "F.Mask" user "Board Geometry/Soldermask Top")
		(3 "B.Mask" user "Board Geometry/Soldermask Bottom")
		(17 "Dwgs.User" user "User.Drawings")
		(19 "Cmts.User" user "User.Comments")
		(21 "Eco1.User" user "User.Eco1")
		(23 "Eco2.User" user "User.Eco2")
		(25 "Edge.Cuts" user "Board Geometry/Outline")
		(27 "Margin" user)
		(31 "F.CrtYd" user "Package Geometry/Place Bound Top")
		(29 "B.CrtYd" user "Package Geometry/Place Bound Bottom")
		(35 "F.Fab" user "Ref Des/Assembly Top")
		(33 "B.Fab" user "Ref Des/Assembly Bottom")
	)
	(footprint ""
		(layer "B.Cu")
		(at 61.597286 -109.481366)
		(property "Reference" "R82"
			(at 0 0 0)
			(layer "B.SilkS")
			(hide yes)
			(effects
				(font
					(size 1.27 1.27)
				)
				(justify mirror)
			)
		)
		(property "Value" ""
			(at 0 0 0)
			(layer "B.Fab")
			(effects
				(font
					(size 1.27 1.27)
				)
				(justify mirror)
			)
		)
		(duplicate_pad_numbers_are_jumpers no)
		(fp_line
			(start -0.7874 -0.4064)
			(end -0.7874 0.4064)
			(stroke
				(width 0.1524)
				(type default)
			)
			(layer "B.SilkS")
		)
		(fp_line
			(start -0.7874 0.4064)
			(end 0.7874 0.4064)
			(stroke
				(width 0.1524)
				(type default)
			)
			(layer "B.SilkS")
		)
		(fp_line
			(start 0.7874 -0.4064)
			(end -0.7874 -0.4064)
			(stroke
				(width 0.1524)
				(type default)
			)
			(layer "B.SilkS")
		)
		(fp_line
			(start 0.7874 0.4064)
			(end 0.7874 -0.4064)
			(stroke
				(width 0.1524)
				(type default)
			)
			(layer "B.SilkS")
		)
		(fp_line
			(start -0.67945 -0.3048)
			(end -0.67945 0.3048)
			(stroke
				(width 0.1)
				(type default)
			)
			(layer "B.Fab")
		)
		(fp_line
			(start -0.67945 0.3048)
			(end -0.120396 0.3048)
			(stroke
				(width 0.1)
				(type default)
			)
			(layer "B.Fab")
		)
		(fp_line
			(start -0.12065 -0.3048)
			(end -0.67945 -0.3048)
			(stroke
				(width 0.1)
				(type default)
			)
			(layer "B.Fab")
		)
		(fp_line
			(start -0.12065 -0.2794)
			(end -0.12065 -0.3048)
			(stroke
				(width 0.1)
				(type default)
			)
			(layer "B.Fab")
		)
		(fp_line
			(start -0.120396 0.2794)
			(end 0.12065 0.2794)
			(stroke
				(width 0.1)
				(type default)
			)
			(layer "B.Fab")
		)
		(fp_line
			(start -0.120396 0.3048)
			(end -0.120396 0.2794)
			(stroke
				(width 0.1)
				(type default)
			)
			(layer "B.Fab")
		)
		(fp_line
			(start 0.12065 -0.305054)
			(end 0.12065 -0.2794)
			(stroke
				(width 0.1)
				(type default)
			)
			(layer "B.Fab")
		)
		(fp_line
			(start 0.12065 -0.2794)
			(end -0.12065 -0.2794)
			(stroke
				(width 0.1)
				(type default)
			)
			(layer "B.Fab")
		)
		(fp_line
			(start 0.12065 0.2794)
			(end 0.12065 0.3048)
			(stroke
				(width 0.1)
				(type default)
			)
			(layer "B.Fab")
		)
		(fp_line
			(start 0.12065 0.3048)
			(end 0.67945 0.3048)
			(stroke
				(width 0.1)
				(type default)
			)
			(layer "B.Fab")
		)
		(fp_line
			(start 0.67945 -0.305054)
			(end 0.12065 -0.305054)
			(stroke
				(width 0.1)
				(type default)
			)
			(layer "B.Fab")
		)
		(fp_line
			(start 0.67945 0.3048)
			(end 0.67945 -0.305054)
			(stroke
				(width 0.1)
				(type default)
			)
			(layer "B.Fab")
		)
		(pad "1" smd circle
			(at 0.40005 0 180)
			(size 0 0)
			(layers "B.Cu" "B.Mask" "B.Paste")
			(net "NIC1_BIF1_N")
		)
		(pad "2" smd circle
			(at -0.40005 0 180)
			(size 0 0)
			(layers "B.Cu" "B.Mask" "B.Paste")
			(net "P3V3_AUX")
		)
	)
	(footprint ""
		(layer "B.Cu")
		(at 119.347488 -304.157634 180)
		(property "Reference" "PR81"
			(at 0 0 0)
			(layer "B.SilkS")
			(hide yes)
			(effects
				(font
					(size 1.27 1.27)
				)
				(justify mirror)
			)
		)
		(property "Value" ""
			(at 0 0 0)
			(layer "B.Fab")
			(effects
				(font
					(size 1.27 1.27)
				)
				(justify mirror)
			)
		)
		(duplicate_pad_numbers_are_jumpers no)
		(fp_line
			(start 0.7874 0.4064)
			(end 0.7874 -0.4064)
			(stroke
				(width 0.1524)
				(type default)
			)
			(layer "B.SilkS")
		)
		(fp_line
			(start 0.7874 -0.4064)
			(end -0.7874 -0.4064)
			(stroke
				(width 0.1524)
				(type default)
			)
			(layer "B.SilkS")
		)
		(fp_line
			(start -0.7874 0.4064)
			(end 0.7874 0.4064)
			(stroke
				(width 0.1524)
				(type default)
			)
			(layer "B.SilkS")
		)
		(fp_line
			(start -0.7874 -0.4064)
			(end -0.7874 0.4064)
			(stroke
				(width 0.1524)
				(type default)
			)
			(layer "B.SilkS")
		)
		(fp_line
			(start 0.67945 0.3048)
			(end 0.67945 -0.305054)
			(stroke
				(width 0.1)
				(type default)
			)
			(layer "B.Fab")
		)
		(fp_line
			(start 0.67945 -0.305054)
			(end 0.12065 -0.305054)
			(stroke
				(width 0.1)
				(type default)
			)
			(layer "B.Fab")
		)
		(fp_line
			(start 0.12065 0.3048)
			(end 0.67945 0.3048)
			(stroke
				(width 0.1)
				(type default)
			)
			(layer "B.Fab")
		)
		(fp_line
			(start 0.12065 0.2794)
			(end 0.12065 0.3048)
			(stroke
				(width 0.1)
				(type default)
			)
			(layer "B.Fab")
		)
		(fp_line
			(start 0.12065 -0.2794)
			(end -0.12065 -0.2794)
			(stroke
				(width 0.1)
				(type default)
			)
			(layer "B.Fab")
		)
		(fp_line
			(start 0.12065 -0.305054)
			(end 0.12065 -0.2794)
			(stroke
				(width 0.1)
				(type default)
			)
			(layer "B.Fab")
		)
		(fp_line
			(start -0.120396 0.3048)
			(end -0.120396 0.2794)
			(stroke
				(width 0.1)
				(type default)
			)
			(layer "B.Fab")
		)
		(fp_line
			(start -0.120396 0.2794)
			(end 0.12065 0.2794)
			(stroke
				(width 0.1)
				(type default)
			)
			(layer "B.Fab")
		)
		(fp_line
			(start -0.12065 -0.2794)
			(end -0.12065 -0.3048)
			(stroke
				(width 0.1)
				(type default)
			)
			(layer "B.Fab")
		)
		(fp_line
			(start -0.12065 -0.3048)
			(end -0.67945 -0.3048)
			(stroke
				(width 0.1)
				(type default)
			)
			(layer "B.Fab")
		)
		(fp_line
			(start -0.67945 0.3048)
			(end -0.120396 0.3048)
			(stroke
				(width 0.1)
				(type default)
			)
			(layer "B.Fab")
		)
		(fp_line
			(start -0.67945 -0.3048)
			(end -0.67945 0.3048)
			(stroke
				(width 0.1)
				(type default)
			)
			(layer "B.Fab")
		)
		(pad "1" smd circle
			(at 0.40005 0)
			(size 0 0)
			(layers "B.Cu" "B.Mask" "B.Paste")
			(net "SH_P0V8_PEX1_RGND1")
		)
		(pad "2" smd circle
			(at -0.40005 0)
			(size 0 0)
			(layers "B.Cu" "B.Mask" "B.Paste")
			(net "GND")
		)
	)
	(footprint ""
		(layer "B.Cu")
		(at 49.1998 -291.624766)
		(property "Reference" "C1103"
			(at 0 0 0)
			(layer "B.SilkS")
			(hide yes)
			(effects
				(font
					(size 1.27 1.27)
				)
				(justify mirror)
			)
		)
		(property "Value" ""
			(at 0 0 0)
			(layer "B.Fab")
			(effects
				(font
					(size 1.27 1.27)
				)
				(justify mirror)
			)
		)
		(duplicate_pad_numbers_are_jumpers no)
		(fp_line
			(start -0.299974 -0.150114)
			(end -0.299974 0.150114)
			(stroke
				(width 0.1)
				(type default)
			)
			(layer "B.Fab")
		)
		(fp_line
			(start -0.299974 0.150114)
			(end 0.299974 0.150114)
			(stroke
				(width 0.1)
				(type default)
			)
			(layer "B.Fab")
		)
		(fp_line
			(start 0.299974 -0.150114)
			(end -0.299974 -0.150114)
			(stroke
				(width 0.1)
				(type default)
			)
			(layer "B.Fab")
		)
		(fp_line
			(start 0.299974 0.150114)
			(end 0.299974 -0.150114)
			(stroke
				(width 0.1)
				(type default)
			)
			(layer "B.Fab")
		)
		(pad "1" smd rect
			(at 0.2667 0 180)
			(size 0.3048 0.381)
			(layers "B.Cu" "B.Mask" "B.Paste")
			(net "P0V8_PEX0")
		)
		(pad "2" smd rect
			(at -0.2667 0 180)
			(size 0.3048 0.381)
			(layers "B.Cu" "B.Mask" "B.Paste")
			(net "GND")
		)
	)
	(footprint ""
		(layer "B.Cu")
		(at 388.366 -227.203 90)
		(property "Reference" "R928"
			(at 0 0 90)
			(layer "B.SilkS")
			(hide yes)
			(effects
				(font
					(size 1.27 1.27)
				)
				(justify mirror)
			)
		)
		(property "Value" ""
			(at 0 0 90)
			(layer "B.Fab")
			(effects
				(font
					(size 1.27 1.27)
				)
				(justify mirror)
			)
		)
		(duplicate_pad_numbers_are_jumpers no)
		(fp_line
			(start 0.7874 -0.4064)
			(end -0.7874 -0.4064)
			(stroke
				(width 0.1524)
				(type default)
			)
			(layer "B.SilkS")
		)
		(fp_line
			(start -0.7874 -0.4064)
			(end -0.7874 0.4064)
			(stroke
				(width 0.1524)
				(type default)
			)
			(layer "B.SilkS")
		)
		(fp_line
			(start 0.7874 0.4064)
			(end 0.7874 -0.4064)
			(stroke
				(width 0.1524)
				(type default)
			)
			(layer "B.SilkS")
		)
		(fp_line
			(start -0.7874 0.4064)
			(end 0.7874 0.4064)
			(stroke
				(width 0.1524)
				(type default)
			)
			(layer "B.SilkS")
		)
		(fp_line
			(start 0.67945 -0.305054)
			(end 0.12065 -0.305054)
			(stroke
				(width 0.1)
				(type default)
			)
			(layer "B.Fab")
		)
		(fp_line
			(start 0.12065 -0.305054)
			(end 0.12065 -0.2794)
			(stroke
				(width 0.1)
				(type default)
			)
			(layer "B.Fab")
		)
		(fp_line
			(start -0.12065 -0.3048)
			(end -0.67945 -0.3048)
			(stroke
				(width 0.1)
				(type default)
			)
			(layer "B.Fab")
		)
		(fp_line
			(start -0.67945 -0.3048)
			(end -0.67945 0.3048)
			(stroke
				(width 0.1)
				(type default)
			)
			(layer "B.Fab")
		)
		(fp_line
			(start 0.12065 -0.2794)
			(end -0.12065 -0.2794)
			(stroke
				(width 0.1)
				(type default)
			)
			(layer "B.Fab")
		)
		(fp_line
			(start -0.12065 -0.2794)
			(end -0.12065 -0.3048)
			(stroke
				(width 0.1)
				(type default)
			)
			(layer "B.Fab")
		)
		(fp_line
			(start 0.12065 0.2794)
			(end 0.12065 0.3048)
			(stroke
				(width 0.1)
				(type default)
			)
			(layer "B.Fab")
		)
		(fp_line
			(start -0.120396 0.2794)
			(end 0.12065 0.2794)
			(stroke
				(width 0.1)
				(type default)
			)
			(layer "B.Fab")
		)
		(fp_line
			(start 0.67945 0.3048)
			(end 0.67945 -0.305054)
			(stroke
				(width 0.1)
				(type default)
			)
			(layer "B.Fab")
		)
		(fp_line
			(start 0.12065 0.3048)
			(end 0.67945 0.3048)
			(stroke
				(width 0.1)
				(type default)
			)
			(layer "B.Fab")
		)
		(fp_line
			(start -0.120396 0.3048)
			(end -0.120396 0.2794)
			(stroke
				(width 0.1)
				(type default)
			)
			(layer "B.Fab")
		)
		(fp_line
			(start -0.67945 0.3048)
			(end -0.120396 0.3048)
			(stroke
				(width 0.1)
				(type default)
			)
			(layer "B.Fab")
		)
		(pad "1" smd circle
			(at 0.40005 0 270)
			(size 0 0)
			(layers "B.Cu" "B.Mask" "B.Paste")
			(net "UART_PEX1_SDB_RX")
		)
		(pad "2" smd circle
			(at -0.40005 0 270)
			(size 0 0)
			(layers "B.Cu" "B.Mask" "B.Paste")
			(net "UART_PEX1_SDB_R_RX")
		)
	)
	(footprint ""
		(layer "B.Cu")
		(at 400.824954 -297.79976 -90)
		(property "Reference" "C1882"
			(at 0 0 90)
			(layer "B.SilkS")
			(hide yes)
			(effects
				(font
					(size 1.27 1.27)
				)
				(justify mirror)
			)
		)
		(property "Value" ""
			(at 0 0 90)
			(layer "B.Fab")
			(effects
				(font
					(size 1.27 1.27)
				)
				(justify mirror)
			)
		)
		(duplicate_pad_numbers_are_jumpers no)
		(fp_line
			(start -0.299974 0.150114)
			(end 0.299974 0.150114)
			(stroke
				(width 0.1)
				(type default)
			)
			(layer "B.Fab")
		)
		(fp_line
			(start 0.299974 0.150114)
			(end 0.299974 -0.150114)
			(stroke
				(width 0.1)
				(type default)
			)
			(layer "B.Fab")
		)
		(fp_line
			(start -0.299974 -0.150114)
			(end -0.299974 0.150114)
			(stroke
				(width 0.1)
				(type default)
			)
			(layer "B.Fab")
		)
		(fp_line
			(start 0.299974 -0.150114)
			(end -0.299974 -0.150114)
			(stroke
				(width 0.1)
				(type default)
			)
			(layer "B.Fab")
		)
		(pad "1" smd rect
			(at 0.2667 0 90)
			(size 0.3048 0.381)
			(layers "B.Cu" "B.Mask" "B.Paste")
			(net "P0V8_PEX3")
		)
		(pad "2" smd rect
			(at -0.2667 0 90)
			(size 0.3048 0.381)
			(layers "B.Cu" "B.Mask" "B.Paste")
			(net "GND")
		)
	)
	(footprint ""
		(layer "B.Cu")
		(at 54.899814 -292.099746 90)
		(property "Reference" "C1219"
			(at 0 0 90)
			(layer "B.SilkS")
			(hide yes)
			(effects
				(font
					(size 1.27 1.27)
				)
				(justify mirror)
			)
		)
		(property "Value" ""
			(at 0 0 90)
			(layer "B.Fab")
			(effects
				(font
					(size 1.27 1.27)
				)
				(justify mirror)
			)
		)
		(duplicate_pad_numbers_are_jumpers no)
		(fp_line
			(start 0.299974 -0.150114)
			(end -0.299974 -0.150114)
			(stroke
				(width 0.1)
				(type default)
			)
			(layer "B.Fab")
		)
		(fp_line
			(start -0.299974 -0.150114)
			(end -0.299974 0.150114)
			(stroke
				(width 0.1)
				(type default)
			)
			(layer "B.Fab")
		)
		(fp_line
			(start 0.299974 0.150114)
			(end 0.299974 -0.150114)
			(stroke
				(width 0.1)
				(type default)
			)
			(layer "B.Fab")
		)
		(fp_line
			(start -0.299974 0.150114)
			(end 0.299974 0.150114)
			(stroke
				(width 0.1)
				(type default)
			)
			(layer "B.Fab")
		)
		(pad "1" smd rect
			(at 0.2667 0 270)
			(size 0.3048 0.381)
			(layers "B.Cu" "B.Mask" "B.Paste")
			(net "P0V8_SERDES_VDDA_PEX0")
		)
		(pad "2" smd rect
			(at -0.2667 0 270)
			(size 0.3048 0.381)
			(layers "B.Cu" "B.Mask" "B.Paste")
			(net "GND")
		)
	)
	(footprint ""
		(layer "B.Cu")
		(at 244.901212 -289.856926 180)
		(property "Reference" "PC994"
			(at 0 0 0)
			(layer "B.SilkS")
			(hide yes)
			(effects
				(font
					(size 1.27 1.27)
				)
				(justify mirror)
			)
		)
		(property "Value" ""
			(at 0 0 0)
			(layer "B.Fab")
			(effects
				(font
					(size 1.27 1.27)
				)
				(justify mirror)
			)
		)
		(duplicate_pad_numbers_are_jumpers no)
		(fp_line
			(start 1.524 0.762)
			(end 1.524 -0.762)
			(stroke
				(width 0.1524)
				(type default)
			)
			(layer "B.SilkS")
		)
		(fp_line
			(start 1.524 -0.762)
			(end -1.524 -0.762)
			(stroke
				(width 0.1524)
				(type default)
			)
			(layer "B.SilkS")
		)
		(fp_line
			(start -1.524 0.762)
			(end 1.524 0.762)
			(stroke
				(width 0.1524)
				(type default)
			)
			(layer "B.SilkS")
		)
		(fp_line
			(start -1.524 -0.762)
			(end -1.524 0.762)
			(stroke
				(width 0.1524)
				(type default)
			)
			(layer "B.SilkS")
		)
		(fp_line
			(start 1.1049 0.724916)
			(end -1.1049 0.724916)
			(stroke
				(width 0.1)
				(type default)
			)
			(layer "B.Fab")
		)
		(fp_line
			(start 1.1049 -0.724916)
			(end 1.1049 0.724916)
			(stroke
				(width 0.1)
				(type default)
			)
			(layer "B.Fab")
		)
		(fp_line
			(start -1.1049 0.724916)
			(end -1.1049 -0.724916)
			(stroke
				(width 0.1)
				(type default)
			)
			(layer "B.Fab")
		)
		(fp_line
			(start -1.1049 -0.724916)
			(end 1.1049 -0.724916)
			(stroke
				(width 0.1)
				(type default)
			)
			(layer "B.Fab")
		)
		(pad "1" smd rect
			(at 0.889 0 180)
			(size 1.016 1.27)
			(layers "B.Cu" "B.Mask" "B.Paste")
			(net "P1V25_PEX2_R")
		)
		(pad "2" smd rect
			(at -0.889 0 180)
			(size 1.016 1.27)
			(layers "B.Cu" "B.Mask" "B.Paste")
			(net "GND")
		)
	)
	(footprint ""
		(layer "B.Cu")
		(at 53.949854 -303.499774 -90)
		(property "Reference" "C2916"
			(at 0 0 90)
			(layer "B.SilkS")
			(hide yes)
			(effects
				(font
					(size 1.27 1.27)
				)
				(justify mirror)
			)
		)
		(property "Value" ""
			(at 0 0 90)
			(layer "B.Fab")
			(effects
				(font
					(size 1.27 1.27)
				)
				(justify mirror)
			)
		)
		(duplicate_pad_numbers_are_jumpers no)
		(fp_line
			(start -0.299974 0.150114)
			(end 0.299974 0.150114)
			(stroke
				(width 0.1)
				(type default)
			)
			(layer "B.Fab")
		)
		(fp_line
			(start 0.299974 0.150114)
			(end 0.299974 -0.150114)
			(stroke
				(width 0.1)
				(type default)
			)
			(layer "B.Fab")
		)
		(fp_line
			(start -0.299974 -0.150114)
			(end -0.299974 0.150114)
			(stroke
				(width 0.1)
				(type default)
			)
			(layer "B.Fab")
		)
		(fp_line
			(start 0.299974 -0.150114)
			(end -0.299974 -0.150114)
			(stroke
				(width 0.1)
				(type default)
			)
			(layer "B.Fab")
		)
		(pad "1" smd rect
			(at 0.2667 0 90)
			(size 0.3048 0.381)
			(layers "B.Cu" "B.Mask" "B.Paste")
			(net "P1V25_PEX0")
		)
		(pad "2" smd rect
			(at -0.2667 0 90)
			(size 0.3048 0.381)
			(layers "B.Cu" "B.Mask" "B.Paste")
			(net "GND")
		)
	)
	(footprint ""
		(layer "B.Cu")
		(at 170.999912 -299.699934 -90)
		(property "Reference" "C1476"
			(at 0 0 90)
			(layer "B.SilkS")
			(hide yes)
			(effects
				(font
					(size 1.27 1.27)
				)
				(justify mirror)
			)
		)
		(property "Value" ""
			(at 0 0 90)
			(layer "B.Fab")
			(effects
				(font
					(size 1.27 1.27)
				)
				(justify mirror)
			)
		)
		(duplicate_pad_numbers_are_jumpers no)
		(fp_line
			(start -0.299974 0.150114)
			(end 0.299974 0.150114)
			(stroke
				(width 0.1)
				(type default)
			)
			(layer "B.Fab")
		)
		(fp_line
			(start 0.299974 0.150114)
			(end 0.299974 -0.150114)
			(stroke
				(width 0.1)
				(type default)
			)
			(layer "B.Fab")
		)
		(fp_line
			(start -0.299974 -0.150114)
			(end -0.299974 0.150114)
			(stroke
				(width 0.1)
				(type default)
			)
			(layer "B.Fab")
		)
		(fp_line
			(start 0.299974 -0.150114)
			(end -0.299974 -0.150114)
			(stroke
				(width 0.1)
				(type default)
			)
			(layer "B.Fab")
		)
		(pad "1" smd rect
			(at 0.2667 0 90)
			(size 0.3048 0.381)
			(layers "B.Cu" "B.Mask" "B.Paste")
			(net "P0V8_SERDES_VDDA_PEX1")
		)
		(pad "2" smd rect
			(at -0.2667 0 90)
			(size 0.3048 0.381)
			(layers "B.Cu" "B.Mask" "B.Paste")
			(net "GND")
		)
	)
)
